FILE_TYPE = CONNECTIVITY;
{Allegro Design Entry HDL 17.2-2016 S081 (4005846) 1/11/2022}
"PAGE_NUMBER" = 157;
0"NC";
END.
